(kicad_pcb
	(version 20260206)
	(generator "pcbnew")
	(generator_version "10.0")
	(general
		(thickness 1.21888)
		(legacy_teardrops no)
	)
	(paper "A4")
	(title_block
		(title "timecard-v8 — TimeCard-DC-V8_EXP.PcbDoc")
		(comment 1 "Time Appliance Project (Time Card) / footprints 10-17 of 288")
	)
	(layers
		(0 "F.Cu" signal "TOP")
		(4 "In1.Cu" signal "SGND")
		(6 "In2.Cu" signal "IN1")
		(8 "In3.Cu" signal "IN2")
		(10 "In4.Cu" signal "SGND1")
		(2 "B.Cu" signal "BOTTOM")
		(9 "F.Adhes" user "F.Adhesive")
		(11 "B.Adhes" user "B.Adhesive")
		(13 "F.Paste" user "Top Paste")
		(15 "B.Paste" user "Bottom Paste")
		(5 "F.SilkS" user "Top Overlay")
		(7 "B.SilkS" user "Bottom Overlay")
		(1 "F.Mask" user "Top Solder")
		(3 "B.Mask" user "Bottom Solder")
		(17 "Dwgs.User" user "User.Drawings")
		(19 "Cmts.User" user "User.Comments")
		(21 "Eco1.User" user "User.Eco1")
		(23 "Eco2.User" user "User.Eco2")
		(25 "Edge.Cuts" user)
		(27 "Margin" user)
		(31 "F.CrtYd" user "Top Courtyard")
		(29 "B.CrtYd" user "Bottom Courtyard")
		(35 "F.Fab" user "Top Component Center")
		(33 "B.Fab" user "Bottom Component Center")
	)
	(footprint "Vault:FP-C1005-050-0_05-IPC_A"
		(layer "F.Cu")
		(at 203.7261 111.8162 90)
		(property "Reference" "C5"
			(at -1.4 -0.293345 270)
			(unlocked yes)
			(layer "F.SilkS")
			(effects
				(font
					(size 0.762 0.762)
					(thickness 0.2286)
				)
				(justify left bottom)
			)
		)
		(property "Value" "2.2uF_16V_0402"
			(at -16.624845 29.5119 0)
			(unlocked yes)
			(layer "F.SilkS")
			(hide yes)
			(effects
				(font
					(size 0.762 0.762)
					(thickness 0.2286)
				)
				(justify left bottom)
			)
		)
		(sheetname "POWER")
		(sheetfile "POWER.kicad_sch")
		(duplicate_pad_numbers_are_jumpers no)
		(fp_line
			(start -0.83624 -0.73623)
			(end 0.83624 -0.73623)
			(stroke
				(width 0.2)
				(type solid)
			)
			(layer "F.SilkS")
		)
		(fp_line
			(start -0.83624 0.73624)
			(end 0.83624 0.73624)
			(stroke
				(width 0.2)
				(type solid)
			)
			(layer "F.SilkS")
		)
		(fp_line
			(start 1.03624 -0.53623)
			(end 1.03624 0.53624)
			(stroke
				(width 0.2)
				(type solid)
			)
			(layer "F.CrtYd")
		)
		(fp_line
			(start -1.03624 -0.53623)
			(end 1.03624 -0.53623)
			(stroke
				(width 0.2)
				(type solid)
			)
			(layer "F.CrtYd")
		)
		(fp_line
			(start -1.03624 -0.53623)
			(end -1.03624 0.53624)
			(stroke
				(width 0.2)
				(type solid)
			)
			(layer "F.CrtYd")
		)
		(fp_line
			(start -1.03624 0.53624)
			(end 1.03624 0.53624)
			(stroke
				(width 0.2)
				(type solid)
			)
			(layer "F.CrtYd")
		)
		(fp_line
			(start 1.03624 -0.53623)
			(end 1.03624 0.53624)
			(stroke
				(width 0.2)
				(type solid)
			)
			(layer "F.Fab")
		)
		(fp_line
			(start -1.03624 -0.53623)
			(end 1.03624 -0.53623)
			(stroke
				(width 0.2)
				(type solid)
			)
			(layer "F.Fab")
		)
		(fp_line
			(start -1.03624 -0.53623)
			(end -1.03624 0.53624)
			(stroke
				(width 0.2)
				(type solid)
			)
			(layer "F.Fab")
		)
		(fp_line
			(start 0 -0.5)
			(end 0 0.5)
			(stroke
				(width 0.1)
				(type solid)
			)
			(layer "F.Fab")
		)
		(fp_line
			(start -0.5 0)
			(end 0.5 0)
			(stroke
				(width 0.1)
				(type solid)
			)
			(layer "F.Fab")
		)
		(fp_line
			(start -1.03624 0.53624)
			(end 1.03624 0.53624)
			(stroke
				(width 0.2)
				(type solid)
			)
			(layer "F.Fab")
		)
		(fp_text user "${REFERENCE}"
			(at -0.00001 0.09602 90)
			(unlocked yes)
			(layer "F.Fab")
			(effects
				(font
					(face "Arial")
					(size 0.63 0.63)
					(thickness 0.1)
				)
				(justify left bottom)
			)
		)
		(pad "1" smd rect
			(at -0.46658 0 90)
			(size 0.73933 0.67248)
			(layers "F.Cu" "F.Mask" "F.Paste")
			(net "P5V_PVDD")
			(solder_mask_margin 0)
			(solder_paste_margin 0)
		)
		(pad "2" smd rect
			(at 0.46657 0 90)
			(size 0.73933 0.67248)
			(layers "F.Cu" "F.Mask" "F.Paste")
			(net "GND")
			(solder_mask_margin 0)
			(solder_paste_margin 0)
		)
	)
	(footprint "Vault:RESC3116X65X50ML20T20"
		(layer "F.Cu")
		(at 155.9123 89.7162)
		(property "Reference" "R47"
			(at 3.9286 -0.073079 0)
			(unlocked yes)
			(layer "F.SilkS")
			(effects
				(font
					(size 0.762 0.762)
					(thickness 0.2286)
				)
			)
		)
		(property "Value" "DNI_0_5%_1206"
			(at 7.27402 3.291071 0)
			(unlocked yes)
			(layer "F.SilkS")
			(hide yes)
			(effects
				(font
					(size 0.762 0.762)
					(thickness 0.2286)
				)
			)
		)
		(sheetname "MAC")
		(sheetfile "MAC.kicad_sch")
		(duplicate_pad_numbers_are_jumpers no)
		(fp_line
			(start -0.35 -0.85)
			(end 0.35 -0.85)
			(stroke
				(width 0.2)
				(type solid)
			)
			(layer "F.SilkS")
		)
		(fp_line
			(start -0.35 0.85)
			(end 0.35 0.85)
			(stroke
				(width 0.2)
				(type solid)
			)
			(layer "F.SilkS")
		)
		(pad "1" smd rect
			(at -1.475 0 90)
			(size 1.9 1.45)
			(layers "F.Cu" "F.Mask" "F.Paste")
			(net "MAC_VCC")
		)
		(pad "2" smd rect
			(at 1.475 0 90)
			(size 1.9 1.45)
			(layers "F.Cu" "F.Mask" "F.Paste")
			(net "+3.3V")
		)
	)
	(footprint "SA53:SolderSocket"
		(layer "F.Cu")
		(at 125.7301 138.2162 90)
		(property "Reference" "SKT10"
			(at -3.426921 -0.575395 0)
			(unlocked yes)
			(layer "F.SilkS")
			(effects
				(font
					(size 0.762 0.762)
					(thickness 0.2286)
				)
			)
		)
		(property "Value" "0332-0-43-80-18-27-10-0"
			(at -2.910071 16.1362 0)
			(unlocked yes)
			(layer "F.SilkS")
			(hide yes)
			(effects
				(font
					(size 0.762 0.762)
					(thickness 0.2286)
				)
			)
		)
		(sheetname "MAC")
		(sheetfile "MAC.kicad_sch")
		(duplicate_pad_numbers_are_jumpers no)
		(pad "1" thru_hole circle
			(at 0 0 90)
			(size 2.54 2.54)
			(drill 2.0066)
			(layers "*.Cu" "*.Mask")
			(remove_unused_layers no)
			(net "MAC_PPS_OUT")
			(thermal_bridge_angle 90)
		)
	)
	(footprint "Resistors:RESC2012X50N"
		(layer "F.Cu")
		(at 199.41136 139.37763)
		(property "Reference" "R18"
			(at -0.68526 -1.068085 0)
			(unlocked yes)
			(layer "F.SilkS")
			(effects
				(font
					(size 0.762 0.762)
					(thickness 0.2286)
				)
				(justify left bottom)
			)
		)
		(property "Value" "CRCW080533R0FKEA"
			(at -5.5249 -8.929165 0)
			(unlocked yes)
			(layer "F.SilkS")
			(hide yes)
			(effects
				(font
					(size 0.762 0.762)
					(thickness 0.2286)
				)
				(justify left bottom)
			)
		)
		(sheetname "PCIe_JTAG")
		(sheetfile "PCIe_JTAG.kicad_sch")
		(duplicate_pad_numbers_are_jumpers no)
		(fp_line
			(start 0 0.762)
			(end 0 -0.762)
			(stroke
				(width 0.1524)
				(type solid)
			)
			(layer "F.SilkS")
		)
		(pad "1" smd rect
			(at -1 0 90)
			(size 1.45 0.95)
			(layers "F.Cu" "F.Mask" "F.Paste")
			(net "FPGA_TCK")
		)
		(pad "2" smd rect
			(at 1 0 90)
			(size 1.45 0.95)
			(layers "F.Cu" "F.Mask" "F.Paste")
			(net "NetR18_2")
		)
	)
	(footprint "Vault:FP-GRM31C-0_2-e0_3_0_8-IPC_C"
		(layer "F.Cu")
		(at 212.1261 103.0162 90)
		(property "Reference" "C12"
			(at 4 -0.393345 270)
			(unlocked yes)
			(layer "F.SilkS")
			(effects
				(font
					(size 0.762 0.762)
					(thickness 0.2286)
				)
				(justify left bottom)
			)
		)
		(property "Value" "4.7uF_50V_1206"
			(at -25.814045 1.90131 0)
			(unlocked yes)
			(layer "F.SilkS")
			(hide yes)
			(effects
				(font
					(size 0.762 0.762)
					(thickness 0.2286)
				)
				(justify left bottom)
			)
		)
		(sheetname "POWER")
		(sheetfile "POWER.kicad_sch")
		(duplicate_pad_numbers_are_jumpers no)
		(fp_line
			(start -0.39847 -0.9)
			(end 0.39846 -0.9)
			(stroke
				(width 0.2)
				(type solid)
			)
			(layer "F.SilkS")
		)
		(fp_line
			(start -0.39847 0.9)
			(end 0.39846 0.9)
			(stroke
				(width 0.2)
				(type solid)
			)
			(layer "F.SilkS")
		)
		(fp_line
			(start 1.9531 -1)
			(end 1.9531 1)
			(stroke
				(width 0.2)
				(type solid)
			)
			(layer "F.CrtYd")
		)
		(fp_line
			(start -1.9531 -1)
			(end 1.9531 -1)
			(stroke
				(width 0.2)
				(type solid)
			)
			(layer "F.CrtYd")
		)
		(fp_line
			(start -1.9531 -1)
			(end -1.9531 1)
			(stroke
				(width 0.2)
				(type solid)
			)
			(layer "F.CrtYd")
		)
		(fp_line
			(start -1.9531 1)
			(end 1.9531 1)
			(stroke
				(width 0.2)
				(type solid)
			)
			(layer "F.CrtYd")
		)
		(fp_line
			(start 1.9531 -1)
			(end 1.9531 1)
			(stroke
				(width 0.2)
				(type solid)
			)
			(layer "F.Fab")
		)
		(fp_line
			(start -1.9531 -1)
			(end 1.9531 -1)
			(stroke
				(width 0.2)
				(type solid)
			)
			(layer "F.Fab")
		)
		(fp_line
			(start -1.9531 -1)
			(end -1.9531 1)
			(stroke
				(width 0.2)
				(type solid)
			)
			(layer "F.Fab")
		)
		(fp_line
			(start 0 -0.5)
			(end 0 0.5)
			(stroke
				(width 0.1)
				(type solid)
			)
			(layer "F.Fab")
		)
		(fp_line
			(start -0.5 0)
			(end 0.5 0)
			(stroke
				(width 0.1)
				(type solid)
			)
			(layer "F.Fab")
		)
		(fp_line
			(start -1.9531 1)
			(end 1.9531 1)
			(stroke
				(width 0.2)
				(type solid)
			)
			(layer "F.Fab")
		)
		(fp_text user "${REFERENCE}"
			(at -0.00001 0.09602 90)
			(unlocked yes)
			(layer "F.Fab")
			(effects
				(font
					(face "Arial")
					(size 0.63 0.63)
					(thickness 0.1)
				)
				(justify left bottom)
			)
		)
		(pad "1" smd rect
			(at -1.27578 0 90)
			(size 1.15464 1.7062)
			(layers "F.Cu" "F.Mask" "F.Paste")
			(net "+12V")
			(solder_mask_margin 0)
			(solder_paste_margin 0)
		)
		(pad "2" smd rect
			(at 1.27578 0 90)
			(size 1.15464 1.7062)
			(layers "F.Cu" "F.Mask" "F.Paste")
			(net "GND")
			(solder_mask_margin 0)
			(solder_paste_margin 0)
		)
	)
	(footprint "Vault:FP-SOD323-MFG"
		(layer "F.Cu")
		(at 223.3261 114.5162)
		(property "Reference" "D21"
			(at 0.828605 1.426931 0)
			(unlocked yes)
			(layer "F.SilkS")
			(effects
				(font
					(size 0.762 0.762)
					(thickness 0.2286)
				)
			)
		)
		(property "Value" "SD103AWS-7-F"
			(at 7.096465 2.452871 0)
			(unlocked yes)
			(layer "F.SilkS")
			(hide yes)
			(effects
				(font
					(size 0.762 0.762)
					(thickness 0.2286)
				)
			)
		)
		(sheetname "POWER")
		(sheetfile "POWER.kicad_sch")
		(duplicate_pad_numbers_are_jumpers no)
		(fp_line
			(start -0.9 -0.7)
			(end 0.9 -0.7)
			(stroke
				(width 0.2)
				(type solid)
			)
			(layer "F.SilkS")
		)
		(fp_line
			(start -0.9 -0.6)
			(end -0.9 -0.7)
			(stroke
				(width 0.2)
				(type solid)
			)
			(layer "F.SilkS")
		)
		(fp_line
			(start -0.9 0.7)
			(end -0.9 0.6)
			(stroke
				(width 0.2)
				(type solid)
			)
			(layer "F.SilkS")
		)
		(fp_line
			(start -0.9 0.7)
			(end 0.9 0.7)
			(stroke
				(width 0.2)
				(type solid)
			)
			(layer "F.SilkS")
		)
		(fp_line
			(start 0.9 -0.6)
			(end 0.9 -0.7)
			(stroke
				(width 0.2)
				(type solid)
			)
			(layer "F.SilkS")
		)
		(fp_line
			(start 0.9 0.7)
			(end 0.9 0.6)
			(stroke
				(width 0.2)
				(type solid)
			)
			(layer "F.SilkS")
		)
		(fp_circle
			(center -1.9 0)
			(end -1.9 -0.125)
			(stroke
				(width 0.25)
				(type solid)
			)
			(fill no)
			(layer "F.SilkS")
		)
		(fp_line
			(start -1.45 -0.8)
			(end 1.45 -0.8)
			(stroke
				(width 0.2)
				(type solid)
			)
			(layer "F.CrtYd")
		)
		(fp_line
			(start -1.45 0.8)
			(end -1.45 -0.8)
			(stroke
				(width 0.2)
				(type solid)
			)
			(layer "F.CrtYd")
		)
		(fp_line
			(start -1.45 0.8)
			(end 1.45 0.8)
			(stroke
				(width 0.2)
				(type solid)
			)
			(layer "F.CrtYd")
		)
		(fp_line
			(start 1.45 0.8)
			(end 1.45 -0.8)
			(stroke
				(width 0.2)
				(type solid)
			)
			(layer "F.CrtYd")
		)
		(fp_line
			(start -1.45 -0.8)
			(end 1.45 -0.8)
			(stroke
				(width 0.2)
				(type solid)
			)
			(layer "F.Fab")
		)
		(fp_line
			(start -1.45 0.8)
			(end -1.45 -0.8)
			(stroke
				(width 0.2)
				(type solid)
			)
			(layer "F.Fab")
		)
		(fp_line
			(start -1.45 0.8)
			(end 1.45 0.8)
			(stroke
				(width 0.2)
				(type solid)
			)
			(layer "F.Fab")
		)
		(fp_line
			(start -0.5 0)
			(end 0.5 0)
			(stroke
				(width 0.1)
				(type solid)
			)
			(layer "F.Fab")
		)
		(fp_line
			(start 0 0.5)
			(end 0 -0.5)
			(stroke
				(width 0.1)
				(type solid)
			)
			(layer "F.Fab")
		)
		(fp_line
			(start 1.45 0.8)
			(end 1.45 -0.8)
			(stroke
				(width 0.2)
				(type solid)
			)
			(layer "F.Fab")
		)
		(fp_text user "${REFERENCE}"
			(at -0.00001 0.10711 360)
			(unlocked yes)
			(layer "F.Fab")
			(effects
				(font
					(face "Arial")
					(size 0.63 0.63)
					(thickness 0.1)
				)
				(justify left bottom)
			)
		)
		(pad "1" smd rect
			(at -1.055 0)
			(size 0.59 0.45)
			(layers "F.Cu" "F.Mask" "F.Paste")
			(net "NetC3_1")
			(solder_mask_margin 0)
			(solder_paste_margin 0)
		)
		(pad "2" smd rect
			(at 1.055 0)
			(size 0.59 0.45)
			(layers "F.Cu" "F.Mask" "F.Paste")
			(net "P5V_PVDD")
			(solder_mask_margin 0)
			(solder_paste_margin 0)
		)
	)
	(footprint "GNSS:GNSS"
		(locked yes)
		(layer "F.Cu")
		(at 84.1536 70.8286)
		(property "Reference" "U9"
			(at -0.6275 -5.419055 0)
			(unlocked yes)
			(layer "F.SilkS")
			(effects
				(font
					(size 0.762 0.762)
					(thickness 0.2286)
				)
				(justify left bottom)
			)
		)
		(property "Value" "RCB-F9T"
			(at -9.8007 23.073645 0)
			(unlocked yes)
			(layer "F.SilkS")
			(hide yes)
			(effects
				(font
					(size 0.762 0.762)
					(thickness 0.2286)
				)
				(justify left bottom)
			)
		)
		(sheetname "GPS_IMU_SENSORS")
		(sheetfile "GPS_IMU_SENSORS.kicad_sch")
		(duplicate_pad_numbers_are_jumpers no)
		(fp_line
			(start -6.11 -20.47)
			(end 61.07 -20.47)
			(stroke
				(width 0.254)
				(type solid)
			)
			(layer "F.SilkS")
		)
		(fp_line
			(start -6.11 11.28)
			(end -6.11 -20.47)
			(stroke
				(width 0.254)
				(type solid)
			)
			(layer "F.SilkS")
		)
		(fp_line
			(start -6.11 11.28)
			(end 61.07 11.28)
			(stroke
				(width 0.254)
				(type solid)
			)
			(layer "F.SilkS")
		)
		(fp_line
			(start 61.07 11.28)
			(end 61.07 -20.47)
			(stroke
				(width 0.254)
				(type solid)
			)
			(layer "F.SilkS")
		)
		(pad "0" thru_hole circle
			(at 0 -2 270)
			(size 0 0)
			(drill 0.76)
			(layers "*.Cu" "*.Mask")
			(remove_unused_layers no)
			(thermal_bridge_angle 90)
		)
		(pad "0" thru_hole circle
			(at 0 2 270)
			(size 0 0)
			(drill 0.76)
			(layers "*.Cu" "*.Mask")
			(remove_unused_layers no)
			(thermal_bridge_angle 90)
		)
		(pad "1" smd rect
			(at -2.2225 3 270)
			(size 1.12 2.105)
			(layers "F.Cu" "F.Mask" "F.Paste")
			(net "+5.0V")
		)
		(pad "2" smd rect
			(at 2.2225 3 270)
			(size 1.12 2.105)
			(layers "F.Cu" "F.Mask" "F.Paste")
			(net "+3.3V")
		)
		(pad "3" smd rect
			(at -2.2225 1 270)
			(size 1.12 2.105)
			(layers "F.Cu" "F.Mask" "F.Paste")
			(net "GPS1_TX")
		)
		(pad "4" smd rect
			(at 2.2225 1 270)
			(size 1.12 2.105)
			(layers "F.Cu" "F.Mask" "F.Paste")
			(net "GPS1_RST")
		)
		(pad "5" smd rect
			(at -2.2225 -1 270)
			(size 1.12 2.105)
			(layers "F.Cu" "F.Mask" "F.Paste")
			(net "GPS1_RX")
		)
		(pad "6" smd rect
			(at 2.2225 -1 270)
			(size 1.12 2.105)
			(layers "F.Cu" "F.Mask" "F.Paste")
			(net "GPS1_TP1")
		)
		(pad "7" smd rect
			(at -2.2225 -3 270)
			(size 1.12 2.105)
			(layers "F.Cu" "F.Mask" "F.Paste")
			(net "GPS1_TP2")
		)
		(pad "8" smd rect
			(at 2.2225 -3 270)
			(size 1.12 2.105)
			(layers "F.Cu" "F.Mask" "F.Paste")
			(net "GND")
		)
	)
	(footprint "SA53:SA53_Header"
		(layer "F.Cu")
		(at 142.66107 112.99691 180)
		(property "Reference" "J31"
			(at 3.046095 -8.854759 180)
			(unlocked yes)
			(layer "F.SilkS")
			(effects
				(font
					(size 0.762 0.762)
					(thickness 0.2286)
				)
			)
		)
		(property "Value" "SA53_Header"
			(at 7.655515 4.548351 180)
			(unlocked yes)
			(layer "F.SilkS")
			(hide yes)
			(effects
				(font
					(size 0.762 0.762)
					(thickness 0.2286)
				)
			)
		)
		(sheetname "MAC")
		(sheetfile "MAC.kicad_sch")
		(duplicate_pad_numbers_are_jumpers no)
		(fp_circle
			(center 6.42 0.07199)
			(end 6.42 0.19899)
			(stroke
				(width 0.254)
				(type solid)
			)
			(fill no)
			(layer "F.SilkS")
		)
		(pad "1" smd rect
			(at 5 0.07199 270)
			(size 0.25 1.8)
			(layers "F.Cu" "F.Mask" "F.Paste")
			(net "MAC_PPS_IN1+")
		)
		(pad "2" smd rect
			(at 1 0.07199 270)
			(size 0.25 1.8)
			(layers "F.Cu" "F.Mask" "F.Paste")
			(net "MAC_USB+")
		)
		(pad "3" smd rect
			(at 5 -0.43601 270)
			(size 0.25 1.8)
			(layers "F.Cu" "F.Mask" "F.Paste")
			(net "MAC_PPS_IN1-")
		)
		(pad "4" smd rect
			(at 1 -0.43601 270)
			(size 0.25 1.8)
			(layers "F.Cu" "F.Mask" "F.Paste")
			(net "MAC_USB-")
		)
		(pad "5" smd rect
			(at 5 -0.94401 270)
			(size 0.25 1.8)
			(layers "F.Cu" "F.Mask" "F.Paste")
			(net "MAC_PPS_IN0+")
		)
		(pad "6" smd rect
			(at 1 -0.94401 270)
			(size 0.25 1.8)
			(layers "F.Cu" "F.Mask" "F.Paste")
			(net "MAC_USB_PWR")
		)
		(pad "7" smd rect
			(at 5 -1.45201 270)
			(size 0.25 1.8)
			(layers "F.Cu" "F.Mask" "F.Paste")
			(net "MAC_PPS_IN0-")
		)
		(pad "8" smd rect
			(at 1 -1.45201 270)
			(size 0.25 1.8)
			(layers "F.Cu" "F.Mask" "F.Paste")
			(net "GND")
		)
		(pad "9" smd rect
			(at 5 -1.96001 270)
			(size 0.25 1.8)
			(layers "F.Cu" "F.Mask" "F.Paste")
			(net "GND")
		)
		(pad "10" smd rect
			(at 1 -1.96001 270)
			(size 0.25 1.8)
			(layers "F.Cu" "F.Mask" "F.Paste")
		)
		(pad "11" smd rect
			(at 5 -2.46801 270)
			(size 0.25 1.8)
			(layers "F.Cu" "F.Mask" "F.Paste")
		)
		(pad "12" smd rect
			(at 1 -2.46801 270)
			(size 0.25 1.8)
			(layers "F.Cu" "F.Mask" "F.Paste")
		)
		(pad "13" smd rect
			(at 5 -2.97601 270)
			(size 0.25 1.8)
			(layers "F.Cu" "F.Mask" "F.Paste")
		)
		(pad "14" smd rect
			(at 1 -2.97601 270)
			(size 0.25 1.8)
			(layers "F.Cu" "F.Mask" "F.Paste")
		)
		(pad "15" smd rect
			(at 5 -3.48401 270)
			(size 0.25 1.8)
			(layers "F.Cu" "F.Mask" "F.Paste")
			(net "GND")
		)
		(pad "16" smd rect
			(at 1 -3.48401 270)
			(size 0.25 1.8)
			(layers "F.Cu" "F.Mask" "F.Paste")
		)
		(pad "17" smd rect
			(at 5 -3.99201 270)
			(size 0.25 1.8)
			(layers "F.Cu" "F.Mask" "F.Paste")
			(net "MAC_PPS_OUT+")
		)
		(pad "18" smd rect
			(at 1 -3.99201 270)
			(size 0.25 1.8)
			(layers "F.Cu" "F.Mask" "F.Paste")
		)
		(pad "19" smd rect
			(at 5 -4.50001 270)
			(size 0.25 1.8)
			(layers "F.Cu" "F.Mask" "F.Paste")
			(net "MAC_PPS_OUT-")
		)
		(pad "20" smd rect
			(at 1 -4.50001 270)
			(size 0.25 1.8)
			(layers "F.Cu" "F.Mask" "F.Paste")
			(net "MAC_ALARM")
		)
		(zone
			(layer "F.Cu")
			(hatch edge 0.5)
			(connect_pads
				(clearance 0)
			)
			(min_thickness 0.25)
			(keepout
				(tracks allowed)
				(vias allowed)
				(pads allowed)
				(copperpour not_allowed)
				(footprints allowed)
			)
			(placement
				(enabled no)
				(sheetname "")
			)
			(fill
				(thermal_gap 0.5)
				(thermal_bridge_width 0.5)
				(island_removal_mode 0)
			)
			(polygon
				(pts
					(xy 135.99358 120.0662) (xy 135.99359 110.0662) (xy 143.49359 110.0662) (xy 143.49358 120.0662)
				)
			)
		)
	)
)
